(kicad_pcb
	(version 20241229)
	(generator "pcbnew")
	(generator_version "9.0")
	(general
		(thickness 1.6)
		(legacy_teardrops no)
	)
	(paper "A4")
	(title_block
		(title "LPDDR4 testbed")
		(date "2024-03-26")
		(rev "1.2.2")
		(comment 9 "footprints 2-8 of 66")
	)
	(layers
		(0 "F.Cu" signal)
		(4 "In1.Cu" power)
		(6 "In2.Cu" power)
		(8 "In3.Cu" signal)
		(10 "In4.Cu" signal)
		(2 "B.Cu" signal)
		(9 "F.Adhes" user "F.Adhesive")
		(11 "B.Adhes" user "B.Adhesive")
		(13 "F.Paste" user)
		(15 "B.Paste" user)
		(5 "F.SilkS" user "F.Silkscreen")
		(7 "B.SilkS" user "B.Silkscreen")
		(1 "F.Mask" user)
		(3 "B.Mask" user)
		(17 "Dwgs.User" user "User.Drawings")
		(19 "Cmts.User" user "User.Comments")
		(21 "Eco1.User" user "User.Eco1")
		(23 "Eco2.User" user "User.Eco2")
		(25 "Edge.Cuts" user)
		(27 "Margin" user)
		(31 "F.CrtYd" user "F.Courtyard")
		(29 "B.CrtYd" user "B.Courtyard")
		(35 "F.Fab" user)
		(33 "B.Fab" user)
	)
	(footprint "antmicro-footprints:R_0402_1005Metric"
		(layer "F.Cu")
		(at 158.375 87.5)
		(descr "Resistor SMD 0402")
		(tags "resistor SMD 0402")
		(property "Reference" "R2"
			(at 0.9 0.35 0)
			(layer "F.SilkS")
			(effects
				(font
					(size 0.7 0.7)
					(thickness 0.15)
				)
				(justify left bottom)
			)
		)
		(property "Value" "R_0R_0402"
			(at 0 1.4 0)
			(layer "F.Fab")
			(effects
				(font
					(size 0.7 0.7)
					(thickness 0.15)
				)
				(justify left bottom)
			)
		)
		(property "Description" "0R resistor in 0402 package with unspecified tolerance"
			(at 0 0 0)
			(layer "F.Fab")
			(hide yes)
			(effects
				(font
					(size 1.27 1.27)
					(thickness 0.15)
				)
			)
		)
		(property "Author" "Antmicro"
			(at 0 0 0)
			(layer "F.Fab")
			(hide yes)
			(effects
				(font
					(size 1 1)
					(thickness 0.15)
				)
			)
		)
		(property "Current" "1A"
			(at 0 0 0)
			(layer "F.Fab")
			(hide yes)
			(effects
				(font
					(size 1 1)
					(thickness 0.15)
				)
			)
		)
		(property "License" "Apache-2.0"
			(at 0 0 0)
			(layer "F.Fab")
			(hide yes)
			(effects
				(font
					(size 1 1)
					(thickness 0.15)
				)
			)
		)
		(property "MPN" "ERJ2GE0R00X"
			(at 0 0 0)
			(layer "F.Fab")
			(hide yes)
			(effects
				(font
					(size 1 1)
					(thickness 0.15)
				)
			)
		)
		(property "Manufacturer" "PANASONIC"
			(at 0 0 0)
			(layer "F.Fab")
			(hide yes)
			(effects
				(font
					(size 1 1)
					(thickness 0.15)
				)
			)
		)
		(property "Tolerance" ""
			(at 0 0 0)
			(layer "F.Fab")
			(hide yes)
			(effects
				(font
					(size 1 1)
					(thickness 0.15)
				)
			)
		)
		(property "Val" "0R"
			(at 0 0 0)
			(layer "F.Fab")
			(hide yes)
			(effects
				(font
					(size 1 1)
					(thickness 0.15)
				)
			)
		)
		(sheetname "LPDDR4")
		(sheetfile "lpddr4.kicad_sch")
		(attr smd)
		(fp_rect
			(start -0.93 -0.47)
			(end 0.93 0.47)
			(stroke
				(width 0.05)
				(type solid)
			)
			(fill no)
			(layer "F.CrtYd")
		)
		(fp_rect
			(start -0.5 -0.25)
			(end 0.5 0.25)
			(stroke
				(width 0.15)
				(type solid)
			)
			(fill no)
			(layer "F.Fab")
		)
		(pad "1" smd roundrect
			(at -0.485 0)
			(size 0.59 0.64)
			(layers "F.Cu" "F.Mask" "F.Paste")
			(roundrect_rratio 0.25)
			(net 158 "Net-(U1A-ODT_CA_A)")
			(pintype "passive")
		)
		(pad "2" smd roundrect
			(at 0.485 0)
			(size 0.59 0.64)
			(layers "F.Cu" "F.Mask" "F.Paste")
			(roundrect_rratio 0.25)
			(net 229 "ODT_CA_A")
			(pintype "passive")
		)
	)
	(footprint "antmicro-footprints:C_0201"
		(layer "F.Cu")
		(at 151.775 77.45 180)
		(descr "Capacitor SMD 0201")
		(tags "capacitor SMD 0201")
		(property "Reference" "C6"
			(at -0.7 0.4 0)
			(layer "F.SilkS")
			(effects
				(font
					(size 0.7 0.7)
					(thickness 0.15)
				)
				(justify right bottom)
			)
		)
		(property "Value" "C_100n_0201"
			(at 0 1.4 0)
			(layer "F.Fab")
			(effects
				(font
					(size 0.7 0.7)
					(thickness 0.15)
				)
				(justify right bottom)
			)
		)
		(property "Description" " "
			(at 0 0 180)
			(layer "F.Fab")
			(hide yes)
			(effects
				(font
					(size 1.27 1.27)
					(thickness 0.15)
				)
			)
		)
		(property "Author" "Antmicro"
			(at 303.55 154.9 0)
			(layer "F.Fab")
			(hide yes)
			(effects
				(font
					(size 1 1)
					(thickness 0.15)
				)
			)
		)
		(property "Dielectric" ""
			(at 303.55 154.9 0)
			(layer "F.Fab")
			(hide yes)
			(effects
				(font
					(size 1 1)
					(thickness 0.15)
				)
			)
		)
		(property "License" "Apache-2.0"
			(at 303.55 154.9 0)
			(layer "F.Fab")
			(hide yes)
			(effects
				(font
					(size 1 1)
					(thickness 0.15)
				)
			)
		)
		(property "MPN" "CC0201KRX6S5BB104"
			(at 303.55 154.9 0)
			(layer "F.Fab")
			(hide yes)
			(effects
				(font
					(size 1 1)
					(thickness 0.15)
				)
			)
		)
		(property "Manufacturer" "YAGEO"
			(at 303.55 154.9 0)
			(layer "F.Fab")
			(hide yes)
			(effects
				(font
					(size 1 1)
					(thickness 0.15)
				)
			)
		)
		(property "Val" "100n"
			(at 303.55 154.9 0)
			(layer "F.Fab")
			(hide yes)
			(effects
				(font
					(size 1 1)
					(thickness 0.15)
				)
			)
		)
		(property "Voltage" ""
			(at 303.55 154.9 0)
			(layer "F.Fab")
			(hide yes)
			(effects
				(font
					(size 1 1)
					(thickness 0.15)
				)
			)
		)
		(sheetname "LPDDR4")
		(sheetfile "lpddr4.kicad_sch")
		(attr smd)
		(fp_rect
			(start -0.72 -0.38)
			(end 0.72 0.38)
			(stroke
				(width 0.05)
				(type solid)
			)
			(fill no)
			(layer "F.CrtYd")
		)
		(fp_rect
			(start 0.3 0.15)
			(end -0.301 -0.149)
			(stroke
				(width 0.15)
				(type solid)
			)
			(fill no)
			(layer "F.Fab")
		)
		(pad "" smd roundrect
			(at -0.349 -0.002 180)
			(size 0.318 0.36)
			(layers "F.Paste")
			(roundrect_rratio 0.25)
		)
		(pad "" smd roundrect
			(at 0.341 -0.002 180)
			(size 0.318 0.36)
			(layers "F.Paste")
			(roundrect_rratio 0.25)
		)
		(pad "1" smd roundrect
			(at -0.321 -0.002 180)
			(size 0.46 0.4)
			(layers "F.Cu" "F.Mask")
			(roundrect_rratio 0.25)
			(net 36 "GND")
			(pintype "passive")
		)
		(pad "2" smd roundrect
			(at 0.32 -0.002 180)
			(size 0.46 0.4)
			(layers "F.Cu" "F.Mask")
			(roundrect_rratio 0.25)
			(net 188 "VDD2")
			(pintype "passive")
		)
	)
	(footprint "antmicro-footprints:C_0201"
		(layer "F.Cu")
		(at 155.855 88.2 -90)
		(descr "Capacitor SMD 0201")
		(tags "capacitor SMD 0201")
		(property "Reference" "C9"
			(at -1.05 -1.12 90)
			(layer "F.SilkS")
			(effects
				(font
					(size 0.7 0.7)
					(thickness 0.15)
				)
				(justify right bottom)
			)
		)
		(property "Value" "C_100n_0201"
			(at 0 1.4 90)
			(layer "F.Fab")
			(effects
				(font
					(size 0.7 0.7)
					(thickness 0.15)
				)
				(justify right bottom)
			)
		)
		(property "Description" " "
			(at 0 0 270)
			(layer "F.Fab")
			(hide yes)
			(effects
				(font
					(size 1.27 1.27)
					(thickness 0.15)
				)
			)
		)
		(property "Author" "Antmicro"
			(at 67.655 244.055 0)
			(layer "F.Fab")
			(hide yes)
			(effects
				(font
					(size 1 1)
					(thickness 0.15)
				)
			)
		)
		(property "Dielectric" ""
			(at 67.655 244.055 0)
			(layer "F.Fab")
			(hide yes)
			(effects
				(font
					(size 1 1)
					(thickness 0.15)
				)
			)
		)
		(property "License" "Apache-2.0"
			(at 67.655 244.055 0)
			(layer "F.Fab")
			(hide yes)
			(effects
				(font
					(size 1 1)
					(thickness 0.15)
				)
			)
		)
		(property "MPN" "CC0201KRX6S5BB104"
			(at 67.655 244.055 0)
			(layer "F.Fab")
			(hide yes)
			(effects
				(font
					(size 1 1)
					(thickness 0.15)
				)
			)
		)
		(property "Manufacturer" "YAGEO"
			(at 67.655 244.055 0)
			(layer "F.Fab")
			(hide yes)
			(effects
				(font
					(size 1 1)
					(thickness 0.15)
				)
			)
		)
		(property "Val" "100n"
			(at 67.655 244.055 0)
			(layer "F.Fab")
			(hide yes)
			(effects
				(font
					(size 1 1)
					(thickness 0.15)
				)
			)
		)
		(property "Voltage" ""
			(at 67.655 244.055 0)
			(layer "F.Fab")
			(hide yes)
			(effects
				(font
					(size 1 1)
					(thickness 0.15)
				)
			)
		)
		(sheetname "LPDDR4")
		(sheetfile "lpddr4.kicad_sch")
		(attr smd)
		(fp_rect
			(start -0.72 -0.38)
			(end 0.72 0.38)
			(stroke
				(width 0.05)
				(type solid)
			)
			(fill no)
			(layer "F.CrtYd")
		)
		(fp_rect
			(start 0.3 0.15)
			(end -0.301 -0.149)
			(stroke
				(width 0.15)
				(type solid)
			)
			(fill no)
			(layer "F.Fab")
		)
		(pad "" smd roundrect
			(at -0.349 -0.002 270)
			(size 0.318 0.36)
			(layers "F.Paste")
			(roundrect_rratio 0.25)
		)
		(pad "" smd roundrect
			(at 0.341 -0.002 270)
			(size 0.318 0.36)
			(layers "F.Paste")
			(roundrect_rratio 0.25)
		)
		(pad "1" smd roundrect
			(at -0.321 -0.002 270)
			(size 0.46 0.4)
			(layers "F.Cu" "F.Mask")
			(roundrect_rratio 0.25)
			(net 36 "GND")
			(pintype "passive")
		)
		(pad "2" smd roundrect
			(at 0.32 -0.002 270)
			(size 0.46 0.4)
			(layers "F.Cu" "F.Mask")
			(roundrect_rratio 0.25)
			(net 188 "VDD2")
			(pintype "passive")
		)
	)
	(footprint "antmicro-footprints:C_0201"
		(layer "F.Cu")
		(at 155.855 81.2 -90)
		(descr "Capacitor SMD 0201")
		(tags "capacitor SMD 0201")
		(property "Reference" "C11"
			(at -1.45 -1.22 90)
			(layer "F.SilkS")
			(effects
				(font
					(size 0.7 0.7)
					(thickness 0.15)
				)
				(justify right bottom)
			)
		)
		(property "Value" "C_100n_0201"
			(at 0 1.4 90)
			(layer "F.Fab")
			(effects
				(font
					(size 0.7 0.7)
					(thickness 0.15)
				)
				(justify right bottom)
			)
		)
		(property "Description" " "
			(at 0 0 270)
			(layer "F.Fab")
			(hide yes)
			(effects
				(font
					(size 1.27 1.27)
					(thickness 0.15)
				)
			)
		)
		(property "Author" "Antmicro"
			(at 74.655 237.055 0)
			(layer "F.Fab")
			(hide yes)
			(effects
				(font
					(size 1 1)
					(thickness 0.15)
				)
			)
		)
		(property "Dielectric" ""
			(at 74.655 237.055 0)
			(layer "F.Fab")
			(hide yes)
			(effects
				(font
					(size 1 1)
					(thickness 0.15)
				)
			)
		)
		(property "License" "Apache-2.0"
			(at 74.655 237.055 0)
			(layer "F.Fab")
			(hide yes)
			(effects
				(font
					(size 1 1)
					(thickness 0.15)
				)
			)
		)
		(property "MPN" "CC0201KRX6S5BB104"
			(at 74.655 237.055 0)
			(layer "F.Fab")
			(hide yes)
			(effects
				(font
					(size 1 1)
					(thickness 0.15)
				)
			)
		)
		(property "Manufacturer" "YAGEO"
			(at 74.655 237.055 0)
			(layer "F.Fab")
			(hide yes)
			(effects
				(font
					(size 1 1)
					(thickness 0.15)
				)
			)
		)
		(property "Val" "100n"
			(at 74.655 237.055 0)
			(layer "F.Fab")
			(hide yes)
			(effects
				(font
					(size 1 1)
					(thickness 0.15)
				)
			)
		)
		(property "Voltage" ""
			(at 74.655 237.055 0)
			(layer "F.Fab")
			(hide yes)
			(effects
				(font
					(size 1 1)
					(thickness 0.15)
				)
			)
		)
		(sheetname "LPDDR4")
		(sheetfile "lpddr4.kicad_sch")
		(attr smd)
		(fp_rect
			(start -0.72 -0.38)
			(end 0.72 0.38)
			(stroke
				(width 0.05)
				(type solid)
			)
			(fill no)
			(layer "F.CrtYd")
		)
		(fp_rect
			(start 0.3 0.15)
			(end -0.301 -0.149)
			(stroke
				(width 0.15)
				(type solid)
			)
			(fill no)
			(layer "F.Fab")
		)
		(pad "" smd roundrect
			(at -0.349 -0.002 270)
			(size 0.318 0.36)
			(layers "F.Paste")
			(roundrect_rratio 0.25)
		)
		(pad "" smd roundrect
			(at 0.341 -0.002 270)
			(size 0.318 0.36)
			(layers "F.Paste")
			(roundrect_rratio 0.25)
		)
		(pad "1" smd roundrect
			(at -0.321 -0.002 270)
			(size 0.46 0.4)
			(layers "F.Cu" "F.Mask")
			(roundrect_rratio 0.25)
			(net 36 "GND")
			(pintype "passive")
		)
		(pad "2" smd roundrect
			(at 0.32 -0.002 270)
			(size 0.46 0.4)
			(layers "F.Cu" "F.Mask")
			(roundrect_rratio 0.25)
			(net 189 "VDDQ")
			(pintype "passive")
		)
	)
	(footprint "antmicro-footprints:C_0201"
		(layer "F.Cu")
		(at 147.251 94.861)
		(descr "Capacitor SMD 0201")
		(tags "capacitor SMD 0201")
		(property "Reference" "C3"
			(at -0.776 1.089 0)
			(layer "F.SilkS")
			(effects
				(font
					(size 0.7 0.7)
					(thickness 0.15)
				)
				(justify left bottom)
			)
		)
		(property "Value" "C_100n_0201"
			(at 0 1.4 0)
			(layer "F.Fab")
			(effects
				(font
					(size 0.7 0.7)
					(thickness 0.15)
				)
				(justify left bottom)
			)
		)
		(property "Description" " "
			(at 0 0 0)
			(layer "F.Fab")
			(hide yes)
			(effects
				(font
					(size 1.27 1.27)
					(thickness 0.15)
				)
			)
		)
		(property "Author" "Antmicro"
			(at 0 0 0)
			(layer "F.Fab")
			(hide yes)
			(effects
				(font
					(size 1 1)
					(thickness 0.15)
				)
			)
		)
		(property "Dielectric" ""
			(at 0 0 0)
			(layer "F.Fab")
			(hide yes)
			(effects
				(font
					(size 1 1)
					(thickness 0.15)
				)
			)
		)
		(property "License" "Apache-2.0"
			(at 0 0 0)
			(layer "F.Fab")
			(hide yes)
			(effects
				(font
					(size 1 1)
					(thickness 0.15)
				)
			)
		)
		(property "MPN" "CC0201KRX6S5BB104"
			(at 0 0 0)
			(layer "F.Fab")
			(hide yes)
			(effects
				(font
					(size 1 1)
					(thickness 0.15)
				)
			)
		)
		(property "Manufacturer" "YAGEO"
			(at 0 0 0)
			(layer "F.Fab")
			(hide yes)
			(effects
				(font
					(size 1 1)
					(thickness 0.15)
				)
			)
		)
		(property "Val" "100n"
			(at 0 0 0)
			(layer "F.Fab")
			(hide yes)
			(effects
				(font
					(size 1 1)
					(thickness 0.15)
				)
			)
		)
		(property "Voltage" ""
			(at 0 0 0)
			(layer "F.Fab")
			(hide yes)
			(effects
				(font
					(size 1 1)
					(thickness 0.15)
				)
			)
		)
		(sheetname "LPDDR4")
		(sheetfile "lpddr4.kicad_sch")
		(attr smd)
		(fp_rect
			(start -0.72 -0.38)
			(end 0.72 0.38)
			(stroke
				(width 0.05)
				(type solid)
			)
			(fill no)
			(layer "F.CrtYd")
		)
		(fp_rect
			(start 0.3 0.15)
			(end -0.301 -0.149)
			(stroke
				(width 0.15)
				(type solid)
			)
			(fill no)
			(layer "F.Fab")
		)
		(pad "" smd roundrect
			(at -0.349 -0.002)
			(size 0.318 0.36)
			(layers "F.Paste")
			(roundrect_rratio 0.25)
		)
		(pad "" smd roundrect
			(at 0.341 -0.002)
			(size 0.318 0.36)
			(layers "F.Paste")
			(roundrect_rratio 0.25)
		)
		(pad "1" smd roundrect
			(at -0.321 -0.002)
			(size 0.46 0.4)
			(layers "F.Cu" "F.Mask")
			(roundrect_rratio 0.25)
			(net 36 "GND")
			(pintype "passive")
		)
		(pad "2" smd roundrect
			(at 0.32 -0.002)
			(size 0.46 0.4)
			(layers "F.Cu" "F.Mask")
			(roundrect_rratio 0.25)
			(net 188 "VDD2")
			(pintype "passive")
		)
	)
	(footprint "antmicro-footprints:C_0201"
		(layer "F.Cu")
		(at 155.855 84.9 90)
		(descr "Capacitor SMD 0201")
		(tags "capacitor SMD 0201")
		(property "Reference" "C18"
			(at -1.35 1.32 90)
			(layer "F.SilkS")
			(effects
				(font
					(size 0.7 0.7)
					(thickness 0.15)
				)
				(justify left bottom)
			)
		)
		(property "Value" "C_100n_0201"
			(at 0 1.4 90)
			(layer "F.Fab")
			(effects
				(font
					(size 0.7 0.7)
					(thickness 0.15)
				)
				(justify left bottom)
			)
		)
		(property "Description" " "
			(at 0 0 90)
			(layer "F.Fab")
			(hide yes)
			(effects
				(font
					(size 1.27 1.27)
					(thickness 0.15)
				)
			)
		)
		(property "Author" "Antmicro"
			(at 240.755 -70.955 0)
			(layer "F.Fab")
			(hide yes)
			(effects
				(font
					(size 1 1)
					(thickness 0.15)
				)
			)
		)
		(property "Dielectric" ""
			(at 240.755 -70.955 0)
			(layer "F.Fab")
			(hide yes)
			(effects
				(font
					(size 1 1)
					(thickness 0.15)
				)
			)
		)
		(property "License" "Apache-2.0"
			(at 240.755 -70.955 0)
			(layer "F.Fab")
			(hide yes)
			(effects
				(font
					(size 1 1)
					(thickness 0.15)
				)
			)
		)
		(property "MPN" "CC0201KRX6S5BB104"
			(at 240.755 -70.955 0)
			(layer "F.Fab")
			(hide yes)
			(effects
				(font
					(size 1 1)
					(thickness 0.15)
				)
			)
		)
		(property "Manufacturer" "YAGEO"
			(at 240.755 -70.955 0)
			(layer "F.Fab")
			(hide yes)
			(effects
				(font
					(size 1 1)
					(thickness 0.15)
				)
			)
		)
		(property "Val" "100n"
			(at 240.755 -70.955 0)
			(layer "F.Fab")
			(hide yes)
			(effects
				(font
					(size 1 1)
					(thickness 0.15)
				)
			)
		)
		(property "Voltage" ""
			(at 240.755 -70.955 0)
			(layer "F.Fab")
			(hide yes)
			(effects
				(font
					(size 1 1)
					(thickness 0.15)
				)
			)
		)
		(sheetname "LPDDR4")
		(sheetfile "lpddr4.kicad_sch")
		(attr smd)
		(fp_rect
			(start -0.72 -0.38)
			(end 0.72 0.38)
			(stroke
				(width 0.05)
				(type solid)
			)
			(fill no)
			(layer "F.CrtYd")
		)
		(fp_rect
			(start 0.3 0.15)
			(end -0.301 -0.149)
			(stroke
				(width 0.15)
				(type solid)
			)
			(fill no)
			(layer "F.Fab")
		)
		(pad "" smd roundrect
			(at -0.349 -0.002 90)
			(size 0.318 0.36)
			(layers "F.Paste")
			(roundrect_rratio 0.25)
		)
		(pad "" smd roundrect
			(at 0.341 -0.002 90)
			(size 0.318 0.36)
			(layers "F.Paste")
			(roundrect_rratio 0.25)
		)
		(pad "1" smd roundrect
			(at -0.321 -0.002 90)
			(size 0.46 0.4)
			(layers "F.Cu" "F.Mask")
			(roundrect_rratio 0.25)
			(net 36 "GND")
			(pintype "passive")
		)
		(pad "2" smd roundrect
			(at 0.32 -0.002 90)
			(size 0.46 0.4)
			(layers "F.Cu" "F.Mask")
			(roundrect_rratio 0.25)
			(net 188 "VDD2")
			(pintype "passive")
		)
	)
	(footprint "antmicro-footprints:C_0201"
		(layer "F.Cu")
		(at 146.925 77.45)
		(descr "Capacitor SMD 0201")
		(tags "capacitor SMD 0201")
		(property "Reference" "C22"
			(at -1.05 -0.4 0)
			(layer "F.SilkS")
			(effects
				(font
					(size 0.7 0.7)
					(thickness 0.15)
				)
				(justify left bottom)
			)
		)
		(property "Value" "C_100n_0201"
			(at 0 1.4 0)
			(layer "F.Fab")
			(effects
				(font
					(size 0.7 0.7)
					(thickness 0.15)
				)
				(justify left bottom)
			)
		)
		(property "Description" " "
			(at 0 0 0)
			(layer "F.Fab")
			(hide yes)
			(effects
				(font
					(size 1.27 1.27)
					(thickness 0.15)
				)
			)
		)
		(property "Author" "Antmicro"
			(at 0 0 0)
			(layer "F.Fab")
			(hide yes)
			(effects
				(font
					(size 1 1)
					(thickness 0.15)
				)
			)
		)
		(property "Dielectric" ""
			(at 0 0 0)
			(layer "F.Fab")
			(hide yes)
			(effects
				(font
					(size 1 1)
					(thickness 0.15)
				)
			)
		)
		(property "License" "Apache-2.0"
			(at 0 0 0)
			(layer "F.Fab")
			(hide yes)
			(effects
				(font
					(size 1 1)
					(thickness 0.15)
				)
			)
		)
		(property "MPN" "CC0201KRX6S5BB104"
			(at 0 0 0)
			(layer "F.Fab")
			(hide yes)
			(effects
				(font
					(size 1 1)
					(thickness 0.15)
				)
			)
		)
		(property "Manufacturer" "YAGEO"
			(at 0 0 0)
			(layer "F.Fab")
			(hide yes)
			(effects
				(font
					(size 1 1)
					(thickness 0.15)
				)
			)
		)
		(property "Val" "100n"
			(at 0 0 0)
			(layer "F.Fab")
			(hide yes)
			(effects
				(font
					(size 1 1)
					(thickness 0.15)
				)
			)
		)
		(property "Voltage" ""
			(at 0 0 0)
			(layer "F.Fab")
			(hide yes)
			(effects
				(font
					(size 1 1)
					(thickness 0.15)
				)
			)
		)
		(sheetname "LPDDR4")
		(sheetfile "lpddr4.kicad_sch")
		(attr smd)
		(fp_rect
			(start -0.72 -0.38)
			(end 0.72 0.38)
			(stroke
				(width 0.05)
				(type solid)
			)
			(fill no)
			(layer "F.CrtYd")
		)
		(fp_rect
			(start 0.3 0.15)
			(end -0.301 -0.149)
			(stroke
				(width 0.15)
				(type solid)
			)
			(fill no)
			(layer "F.Fab")
		)
		(pad "" smd roundrect
			(at -0.349 -0.002)
			(size 0.318 0.36)
			(layers "F.Paste")
			(roundrect_rratio 0.25)
		)
		(pad "" smd roundrect
			(at 0.341 -0.002)
			(size 0.318 0.36)
			(layers "F.Paste")
			(roundrect_rratio 0.25)
		)
		(pad "1" smd roundrect
			(at -0.321 -0.002)
			(size 0.46 0.4)
			(layers "F.Cu" "F.Mask")
			(roundrect_rratio 0.25)
			(net 36 "GND")
			(pintype "passive")
		)
		(pad "2" smd roundrect
			(at 0.32 -0.002)
			(size 0.46 0.4)
			(layers "F.Cu" "F.Mask")
			(roundrect_rratio 0.25)
			(net 188 "VDD2")
			(pintype "passive")
		)
	)
)
